(kicad_pcb
	(version 20260206)
	(generator "pcbnew")
	(generator_version "10.0")
	(general
		(thickness 1.6)
		(legacy_teardrops no)
	)
	(paper "A4")
	(title_block
		(title "v2-pdb — ms_pdb_v2.brd")
		(comment 1 "Open CloudServer (Microsoft) / footprints 103-110 of 348")
	)
	(layers
		(0 "F.Cu" signal "TOP")
		(4 "In1.Cu" signal "GND")
		(6 "In2.Cu" signal "IN1")
		(8 "In3.Cu" signal "VCC")
		(10 "In4.Cu" signal "VCC1")
		(12 "In5.Cu" signal "IN2")
		(14 "In6.Cu" signal "GND1")
		(2 "B.Cu" signal "BOTTOM")
		(9 "F.Adhes" user "F.Adhesive")
		(11 "B.Adhes" user "B.Adhesive")
		(13 "F.Paste" user "Package Geometry/Pastemask Top")
		(15 "B.Paste" user "Package Geometry/Pastemask Bottom")
		(5 "F.SilkS" user "Ref Des/Silkscreen Top")
		(7 "B.SilkS" user "Ref Des/Silkscreen Bottom")
		(1 "F.Mask" user "Board Geometry/Soldermask Top")
		(3 "B.Mask" user "Board Geometry/Soldermask Bottom")
		(17 "Dwgs.User" user "User.Drawings")
		(19 "Cmts.User" user "User.Comments")
		(21 "Eco1.User" user "User.Eco1")
		(23 "Eco2.User" user "User.Eco2")
		(25 "Edge.Cuts" user "Board Geometry/Outline")
		(27 "Margin" user)
		(31 "F.CrtYd" user "Package Geometry/Place Bound Top")
		(29 "B.CrtYd" user "Package Geometry/Place Bound Bottom")
		(35 "F.Fab" user "Ref Des/Assembly Top")
		(33 "B.Fab" user "Ref Des/Assembly Bottom")
	)
	(footprint ""
		(layer "F.Cu")
		(at 27.16911 -373.43207)
		(property "Reference" "R19"
			(at -3.196844 0.148336 0)
			(unlocked yes)
			(layer "F.SilkS")
			(effects
				(font
					(size 0.7874 0.5842)
					(thickness 0.1524)
				)
				(justify left)
			)
		)
		(property "Value" ""
			(at 0 0 0)
			(layer "F.Fab")
			(effects
				(font
					(size 1.27 1.27)
				)
			)
		)
		(duplicate_pad_numbers_are_jumpers no)
		(fp_line
			(start -0.7874 -0.4064)
			(end 0.7874 -0.4064)
			(stroke
				(width 0.1524)
				(type default)
			)
			(layer "F.SilkS")
		)
		(fp_line
			(start -0.7874 0.4064)
			(end -0.7874 -0.4064)
			(stroke
				(width 0.1524)
				(type default)
			)
			(layer "F.SilkS")
		)
		(fp_line
			(start 0.7874 -0.4064)
			(end 0.7874 0.4064)
			(stroke
				(width 0.1524)
				(type default)
			)
			(layer "F.SilkS")
		)
		(fp_line
			(start 0.7874 0.4064)
			(end -0.7874 0.4064)
			(stroke
				(width 0.1524)
				(type default)
			)
			(layer "F.SilkS")
		)
		(fp_poly
			(pts
				(xy -0.508 0.2794) (xy -0.508 0.2286) (xy -0.635 0.2286) (xy -0.635 -0.254) (xy -0.5334 -0.254)
				(xy -0.5334 -0.2794) (xy 0.5334 -0.2794) (xy 0.5334 -0.254) (xy 0.635 -0.254) (xy 0.635 0.254) (xy 0.5334 0.254)
				(xy 0.5334 0.2794)
			)
			(stroke
				(width 0)
				(type default)
			)
			(fill no)
			(layer "F.CrtYd")
		)
		(pad "1" smd rect
			(at 0.40005 0)
			(size 0.4572 0.508)
			(layers "F.Cu" "F.Mask" "F.Paste")
			(net "PSU5_REMOTE_N")
		)
		(pad "2" smd rect
			(at -0.40005 0)
			(size 0.4572 0.508)
			(layers "F.Cu" "F.Mask" "F.Paste")
			(net "GND")
		)
	)
	(footprint ""
		(layer "F.Cu")
		(at 16.599916 -29.19984)
		(property "Reference" "H11"
			(at 3.43535 -8.642604 0)
			(unlocked yes)
			(layer "F.SilkS")
			(effects
				(font
					(size 0.7874 0.5842)
					(thickness 0.1524)
				)
				(justify left)
			)
		)
		(property "Value" ""
			(at 0 0 0)
			(layer "F.Fab")
			(effects
				(font
					(size 1.27 1.27)
				)
			)
		)
		(duplicate_pad_numbers_are_jumpers no)
		(fp_circle
			(center 0 0)
			(end 7.999984 0)
			(stroke
				(width 0.1524)
				(type default)
			)
			(fill no)
			(layer "F.SilkS")
		)
		(fp_circle
			(center 0 0)
			(end 14.7066 0)
			(stroke
				(width 0.1524)
				(type default)
			)
			(fill no)
			(layer "B.SilkS")
		)
		(fp_poly
			(pts
				(arc
					(start 0 5.0038)
					(mid 0 -5.0038)
					(end 0 5.0038)
				)
			)
			(stroke
				(width 0)
				(type default)
			)
			(fill no)
			(layer "F.CrtYd")
		)
		(pad "" np_thru_hole circle
			(at 0 0)
			(size 4.0132 4.0132)
			(drill 4.0132)
			(layers "*.Cu" "*.Mask")
			(clearance 0.381)
			(thermal_gap 0.381)
		)
		(pad "2" thru_hole circle
			(at 0 -3.50012)
			(size 0.762 0.762)
			(drill 0.5588)
			(layers "*.Cu" "*.Mask")
			(remove_unused_layers no)
			(net "GND")
			(clearance 0.1524)
			(thermal_gap 0.1524)
		)
		(pad "3" thru_hole circle
			(at -2.500122 -2.500122)
			(size 0.762 0.762)
			(drill 0.5588)
			(layers "*.Cu" "*.Mask")
			(remove_unused_layers no)
			(net "GND")
			(clearance 0.1524)
			(thermal_gap 0.1524)
		)
		(pad "4" thru_hole circle
			(at -3.50012 0)
			(size 0.762 0.762)
			(drill 0.5588)
			(layers "*.Cu" "*.Mask")
			(remove_unused_layers no)
			(net "GND")
			(clearance 0.1524)
			(thermal_gap 0.1524)
		)
		(pad "5" thru_hole circle
			(at -2.500122 2.500122)
			(size 0.762 0.762)
			(drill 0.5588)
			(layers "*.Cu" "*.Mask")
			(remove_unused_layers no)
			(net "GND")
			(clearance 0.1524)
			(thermal_gap 0.1524)
		)
		(pad "6" thru_hole circle
			(at 0 3.50012)
			(size 0.762 0.762)
			(drill 0.5588)
			(layers "*.Cu" "*.Mask")
			(remove_unused_layers no)
			(net "GND")
			(clearance 0.1524)
			(thermal_gap 0.1524)
		)
		(pad "7" thru_hole circle
			(at 2.500122 2.500122)
			(size 0.762 0.762)
			(drill 0.5588)
			(layers "*.Cu" "*.Mask")
			(remove_unused_layers no)
			(net "GND")
			(clearance 0.1524)
			(thermal_gap 0.1524)
		)
		(pad "8" thru_hole circle
			(at 3.50012 0)
			(size 0.762 0.762)
			(drill 0.5588)
			(layers "*.Cu" "*.Mask")
			(remove_unused_layers no)
			(net "GND")
			(clearance 0.1524)
			(thermal_gap 0.1524)
		)
		(pad "9" thru_hole circle
			(at 2.500122 -2.500122)
			(size 0.762 0.762)
			(drill 0.5588)
			(layers "*.Cu" "*.Mask")
			(remove_unused_layers no)
			(net "GND")
			(clearance 0.1524)
			(thermal_gap 0.1524)
		)
		(zone
			(layer "F.Cu")
			(hatch none 0.5)
			(connect_pads
				(clearance 0)
			)
			(min_thickness 0.25)
			(keepout
				(tracks not_allowed)
				(vias allowed)
				(pads allowed)
				(copperpour not_allowed)
				(footprints allowed)
			)
			(placement
				(enabled no)
				(sheetname "")
			)
			(fill
				(thermal_gap 0.5)
				(thermal_bridge_width 0.5)
				(island_removal_mode 0)
			)
			(polygon
				(pts
					(arc
						(start 16.599916 -37.20084)
						(mid 8.598916 -29.19984)
						(end 16.599916 -21.19884)
					)
					(arc
						(start 16.599916 -21.19884)
						(mid 18.035016 -22.63394)
						(end 16.599916 -24.06904)
					)
					(arc
						(start 16.599916 -24.06904)
						(mid 11.469116 -29.19984)
						(end 16.599916 -34.33064)
					)
					(arc
						(start 16.599916 -34.33064)
						(mid 18.035016 -35.76574)
						(end 16.599916 -37.20084)
					)
				)
			)
		)
		(zone
			(layer "F.Cu")
			(hatch none 0.5)
			(connect_pads
				(clearance 0)
			)
			(min_thickness 0.25)
			(keepout
				(tracks not_allowed)
				(vias allowed)
				(pads allowed)
				(copperpour not_allowed)
				(footprints allowed)
			)
			(placement
				(enabled no)
				(sheetname "")
			)
			(fill
				(thermal_gap 0.5)
				(thermal_bridge_width 0.5)
				(island_removal_mode 0)
			)
			(polygon
				(pts
					(arc
						(start 16.599916 -37.20084)
						(mid 24.600916 -29.19984)
						(end 16.599916 -21.19884)
					)
					(arc
						(start 16.599916 -21.19884)
						(mid 15.164816 -22.63394)
						(end 16.599916 -24.06904)
					)
					(arc
						(start 16.599916 -24.06904)
						(mid 21.730716 -29.19984)
						(end 16.599916 -34.33064)
					)
					(arc
						(start 16.599916 -34.33064)
						(mid 15.164816 -35.76574)
						(end 16.599916 -37.20084)
					)
				)
			)
		)
		(zone
			(layers "F.Cu" "B.Cu" "In1.Cu" "In2.Cu" "In3.Cu" "In4.Cu" "In5.Cu" "In6.Cu")
			(hatch none 0.5)
			(connect_pads
				(clearance 0)
			)
			(min_thickness 0.25)
			(keepout
				(tracks not_allowed)
				(vias allowed)
				(pads allowed)
				(copperpour not_allowed)
				(footprints allowed)
			)
			(placement
				(enabled no)
				(sheetname "")
			)
			(fill
				(thermal_gap 0.5)
				(thermal_bridge_width 0.5)
				(island_removal_mode 0)
			)
			(polygon
				(pts
					(arc
						(start 16.599916 -26.68778)
						(mid 16.599916 -31.7119)
						(end 16.599916 -26.68778)
					)
				)
			)
		)
	)
	(footprint ""
		(layer "F.Cu")
		(at 69.863208 -350.498664 90)
		(property "Reference" "C62"
			(at 1.14046 -0.108966 90)
			(unlocked yes)
			(layer "F.SilkS")
			(effects
				(font
					(size 0.7874 0.5842)
					(thickness 0.1524)
				)
				(justify left)
			)
		)
		(property "Value" ""
			(at 0 0 90)
			(layer "F.Fab")
			(effects
				(font
					(size 1.27 1.27)
				)
			)
		)
		(duplicate_pad_numbers_are_jumpers no)
		(fp_line
			(start 0.7874 -0.4064)
			(end 0.7874 0.4064)
			(stroke
				(width 0.1524)
				(type default)
			)
			(layer "F.SilkS")
		)
		(fp_line
			(start -0.7874 -0.4064)
			(end 0.7874 -0.4064)
			(stroke
				(width 0.1524)
				(type default)
			)
			(layer "F.SilkS")
		)
		(fp_line
			(start 0 0.381)
			(end 0 -0.381)
			(stroke
				(width 0.1524)
				(type default)
			)
			(layer "F.SilkS")
		)
		(fp_line
			(start 0.7874 0.4064)
			(end -0.7874 0.4064)
			(stroke
				(width 0.1524)
				(type default)
			)
			(layer "F.SilkS")
		)
		(fp_line
			(start -0.7874 0.4064)
			(end -0.7874 -0.4064)
			(stroke
				(width 0.1524)
				(type default)
			)
			(layer "F.SilkS")
		)
		(fp_poly
			(pts
				(xy -0.5334 0.254) (xy -0.635 0.254) (xy -0.635 0.2286) (xy -0.635 -0.254) (xy -0.5334 -0.254) (xy -0.5334 -0.2794)
				(xy 0.5334 -0.2794) (xy 0.5334 -0.254) (xy 0.635 -0.254) (xy 0.635 0.254) (xy 0.5334 0.254) (xy 0.5334 0.2794)
				(xy -0.508 0.2794) (xy -0.5334 0.2794)
			)
			(stroke
				(width 0)
				(type default)
			)
			(fill no)
			(layer "F.CrtYd")
		)
		(pad "1" smd rect
			(at 0.40005 0 90)
			(size 0.4572 0.508)
			(layers "F.Cu" "F.Mask" "F.Paste")
			(net "P12V")
		)
		(pad "2" smd rect
			(at -0.40005 0 90)
			(size 0.4572 0.508)
			(layers "F.Cu" "F.Mask" "F.Paste")
			(net "GND")
		)
	)
	(footprint ""
		(layer "F.Cu")
		(at 39.461948 -199.56907 -90)
		(property "Reference" "R94"
			(at -0.904494 -3.072892 90)
			(unlocked yes)
			(layer "F.SilkS")
			(effects
				(font
					(size 0.7874 0.5842)
					(thickness 0.1524)
				)
				(justify left)
			)
		)
		(property "Value" ""
			(at 0 0 270)
			(layer "F.Fab")
			(effects
				(font
					(size 1.27 1.27)
				)
			)
		)
		(duplicate_pad_numbers_are_jumpers no)
		(fp_line
			(start -0.7874 0.4064)
			(end -0.7874 -0.4064)
			(stroke
				(width 0.1524)
				(type default)
			)
			(layer "F.SilkS")
		)
		(fp_line
			(start 0.7874 0.4064)
			(end -0.7874 0.4064)
			(stroke
				(width 0.1524)
				(type default)
			)
			(layer "F.SilkS")
		)
		(fp_line
			(start -0.7874 -0.4064)
			(end 0.7874 -0.4064)
			(stroke
				(width 0.1524)
				(type default)
			)
			(layer "F.SilkS")
		)
		(fp_line
			(start 0.7874 -0.4064)
			(end 0.7874 0.4064)
			(stroke
				(width 0.1524)
				(type default)
			)
			(layer "F.SilkS")
		)
		(fp_poly
			(pts
				(xy -0.508 0.2794) (xy -0.508 0.2286) (xy -0.635 0.2286) (xy -0.635 -0.254) (xy -0.5334 -0.254)
				(xy -0.5334 -0.2794) (xy 0.5334 -0.2794) (xy 0.5334 -0.254) (xy 0.635 -0.254) (xy 0.635 0.254) (xy 0.5334 0.254)
				(xy 0.5334 0.2794)
			)
			(stroke
				(width 0)
				(type default)
			)
			(fill no)
			(layer "F.CrtYd")
		)
		(pad "1" smd rect
			(at 0.40005 0 270)
			(size 0.4572 0.508)
			(layers "F.Cu" "F.Mask" "F.Paste")
			(net "PSU3_REMOTE_P")
		)
		(pad "2" smd rect
			(at -0.40005 0 270)
			(size 0.4572 0.508)
			(layers "F.Cu" "F.Mask" "F.Paste")
			(net "PSU3_REMOTE_R_P")
		)
	)
	(footprint ""
		(layer "F.Cu")
		(at 39.460424 -198.769478 90)
		(property "Reference" "R118"
			(at -0.484632 1.99009 0)
			(unlocked yes)
			(layer "F.SilkS")
			(effects
				(font
					(size 0.7874 0.5842)
					(thickness 0.1524)
				)
				(justify left)
			)
		)
		(property "Value" ""
			(at 0 0 90)
			(layer "F.Fab")
			(effects
				(font
					(size 1.27 1.27)
				)
			)
		)
		(duplicate_pad_numbers_are_jumpers no)
		(fp_line
			(start 0.7874 -0.4064)
			(end 0.7874 0.4064)
			(stroke
				(width 0.1524)
				(type default)
			)
			(layer "F.SilkS")
		)
		(fp_line
			(start -0.7874 -0.4064)
			(end 0.7874 -0.4064)
			(stroke
				(width 0.1524)
				(type default)
			)
			(layer "F.SilkS")
		)
		(fp_line
			(start 0.7874 0.4064)
			(end -0.7874 0.4064)
			(stroke
				(width 0.1524)
				(type default)
			)
			(layer "F.SilkS")
		)
		(fp_line
			(start -0.7874 0.4064)
			(end -0.7874 -0.4064)
			(stroke
				(width 0.1524)
				(type default)
			)
			(layer "F.SilkS")
		)
		(fp_poly
			(pts
				(xy -0.508 0.2794) (xy -0.508 0.2286) (xy -0.635 0.2286) (xy -0.635 -0.254) (xy -0.5334 -0.254)
				(xy -0.5334 -0.2794) (xy 0.5334 -0.2794) (xy 0.5334 -0.254) (xy 0.635 -0.254) (xy 0.635 0.254) (xy 0.5334 0.254)
				(xy 0.5334 0.2794)
			)
			(stroke
				(width 0)
				(type default)
			)
			(fill no)
			(layer "F.CrtYd")
		)
		(pad "1" smd rect
			(at 0.40005 0 90)
			(size 0.4572 0.508)
			(layers "F.Cu" "F.Mask" "F.Paste")
			(net "PSU3_REMOTE_P")
		)
		(pad "2" smd rect
			(at -0.40005 0 90)
			(size 0.4572 0.508)
			(layers "F.Cu" "F.Mask" "F.Paste")
			(net "PSU3_REMOTE_R2_P")
		)
	)
	(footprint ""
		(layer "F.Cu")
		(at 50.39868 -519.020552 180)
		(property "Reference" "CE24"
			(at 0.751586 5.701792 0)
			(unlocked yes)
			(layer "F.SilkS")
			(effects
				(font
					(size 0.7874 0.5842)
					(thickness 0.1524)
				)
				(justify left)
			)
		)
		(property "Value" ""
			(at 0 0 180)
			(layer "F.Fab")
			(effects
				(font
					(size 1.27 1.27)
				)
			)
		)
		(duplicate_pad_numbers_are_jumpers no)
		(fp_line
			(start 0 -4.2672)
			(end 0 4.2672)
			(stroke
				(width 0.1524)
				(type default)
			)
			(layer "F.SilkS")
		)
		(fp_circle
			(center 0 0)
			(end -4.2672 0)
			(stroke
				(width 0.1524)
				(type default)
			)
			(fill no)
			(layer "F.SilkS")
		)
		(fp_poly
			(pts
				(arc
					(start 0 -4.2672)
					(mid 4.2672 0)
					(end 0 4.2672)
				)
			)
			(stroke
				(width 0)
				(type default)
			)
			(fill yes)
			(layer "F.SilkS")
		)
		(fp_poly
			(pts
				(xy -2.5146 -0.762) (xy -0.9906 -0.762) (xy -0.9906 0.762) (xy -2.5146 0.762)
			)
			(stroke
				(width 0)
				(type default)
			)
			(fill no)
			(layer "B.CrtYd")
		)
		(fp_poly
			(pts
				(arc
					(start 1.7526 0.762)
					(mid 2.291415 -0.538815)
					(end 0.9906 0)
				)
				(arc
					(start 0.9906 0.0254)
					(mid 1.206345 0.546255)
					(end 1.7272 0.762)
				)
			)
			(stroke
				(width 0)
				(type default)
			)
			(fill no)
			(layer "B.CrtYd")
		)
		(fp_poly
			(pts
				(arc
					(start -4.2672 0)
					(mid 4.2672 0)
					(end -4.2672 0)
				)
			)
			(stroke
				(width 0)
				(type default)
			)
			(fill no)
			(layer "F.CrtYd")
		)
		(fp_circle
			(center 0 0)
			(end -4.2672 0)
			(stroke
				(width 0.1)
				(type default)
			)
			(fill no)
			(layer "F.Fab")
		)
		(fp_text user "+"
			(at -5.892292 -1.58115 180)
			(unlocked yes)
			(layer "F.SilkS")
			(effects
				(font
					(size 1.905 1.4224)
					(thickness 0.1524)
				)
				(justify left)
			)
		)
		(fp_text user "+"
			(at -5.6642 -0.34925 180)
			(unlocked yes)
			(layer "F.Fab")
			(effects
				(font
					(size 1.905 1.4224)
					(thickness 0.000001)
				)
				(justify left)
			)
		)
		(pad "1" thru_hole rect
			(at -1.75006 0 180)
			(size 1.397 1.397)
			(drill 0.9144)
			(layers "*.Cu" "*.Mask")
			(remove_unused_layers no)
			(net "P12V")
			(clearance 0.0127)
			(thermal_gap 0.0127)
			(padstack
				(mode front_inner_back)
				(layer "Inner"
					(shape circle)
					(size 1.397 1.397)
					(clearance 0.0127)
				)
				(layer "B.Cu"
					(shape rect)
					(size 1.397 1.397)
					(clearance 0.0127)
				)
			)
		)
		(pad "2" thru_hole circle
			(at 1.75006 0 180)
			(size 1.397 1.397)
			(drill 0.9144)
			(layers "*.Cu" "*.Mask")
			(remove_unused_layers no)
			(net "GND")
			(clearance 0.0127)
			(thermal_gap 0.0127)
		)
	)
	(footprint ""
		(layer "F.Cu")
		(at 50.39868 -463.099658 180)
		(property "Reference" "CE22"
			(at -4.925568 2.154174 0)
			(unlocked yes)
			(layer "F.SilkS")
			(effects
				(font
					(size 0.7874 0.5842)
					(thickness 0.1524)
				)
				(justify left)
			)
		)
		(property "Value" ""
			(at 0 0 180)
			(layer "F.Fab")
			(effects
				(font
					(size 1.27 1.27)
				)
			)
		)
		(duplicate_pad_numbers_are_jumpers no)
		(fp_line
			(start 0 -4.2672)
			(end 0 4.2672)
			(stroke
				(width 0.1524)
				(type default)
			)
			(layer "F.SilkS")
		)
		(fp_circle
			(center 0 0)
			(end -4.2672 0)
			(stroke
				(width 0.1524)
				(type default)
			)
			(fill no)
			(layer "F.SilkS")
		)
		(fp_poly
			(pts
				(arc
					(start 0 -4.2672)
					(mid 4.2672 0)
					(end 0 4.2672)
				)
			)
			(stroke
				(width 0)
				(type default)
			)
			(fill yes)
			(layer "F.SilkS")
		)
		(fp_poly
			(pts
				(xy -2.5146 -0.762) (xy -0.9906 -0.762) (xy -0.9906 0.762) (xy -2.5146 0.762)
			)
			(stroke
				(width 0)
				(type default)
			)
			(fill no)
			(layer "B.CrtYd")
		)
		(fp_poly
			(pts
				(arc
					(start 1.7526 0.762)
					(mid 2.291415 -0.538815)
					(end 0.9906 0)
				)
				(arc
					(start 0.9906 0.0254)
					(mid 1.206345 0.546255)
					(end 1.7272 0.762)
				)
			)
			(stroke
				(width 0)
				(type default)
			)
			(fill no)
			(layer "B.CrtYd")
		)
		(fp_poly
			(pts
				(arc
					(start -4.2672 0)
					(mid 4.2672 0)
					(end -4.2672 0)
				)
			)
			(stroke
				(width 0)
				(type default)
			)
			(fill no)
			(layer "F.CrtYd")
		)
		(fp_circle
			(center 0 0)
			(end -4.2672 0)
			(stroke
				(width 0.1)
				(type default)
			)
			(fill no)
			(layer "F.Fab")
		)
		(fp_text user "+"
			(at -5.6642 -0.34925 180)
			(unlocked yes)
			(layer "F.SilkS")
			(effects
				(font
					(size 1.905 1.4224)
					(thickness 0.1524)
				)
				(justify left)
			)
		)
		(fp_text user "+"
			(at -5.6642 -0.34925 180)
			(unlocked yes)
			(layer "F.Fab")
			(effects
				(font
					(size 1.905 1.4224)
					(thickness 0.000001)
				)
				(justify left)
			)
		)
		(pad "1" thru_hole rect
			(at -1.75006 0 180)
			(size 1.397 1.397)
			(drill 0.9144)
			(layers "*.Cu" "*.Mask")
			(remove_unused_layers no)
			(net "P12V")
			(clearance 0.0127)
			(thermal_gap 0.0127)
			(padstack
				(mode front_inner_back)
				(layer "Inner"
					(shape circle)
					(size 1.397 1.397)
					(clearance 0.0127)
				)
				(layer "B.Cu"
					(shape rect)
					(size 1.397 1.397)
					(clearance 0.0127)
				)
			)
		)
		(pad "2" thru_hole circle
			(at 1.75006 0 180)
			(size 1.397 1.397)
			(drill 0.9144)
			(layers "*.Cu" "*.Mask")
			(remove_unused_layers no)
			(net "GND")
			(clearance 0.0127)
			(thermal_gap 0.0127)
		)
	)
	(footprint ""
		(layer "F.Cu")
		(at 27.577542 -373.832628 -90)
		(property "Reference" "R105"
			(at -1.451356 0.04318 90)
			(unlocked yes)
			(layer "F.SilkS")
			(effects
				(font
					(size 0.7874 0.5842)
					(thickness 0.1524)
				)
				(justify left)
			)
		)
		(property "Value" ""
			(at 0 0 270)
			(layer "F.Fab")
			(effects
				(font
					(size 1.27 1.27)
				)
			)
		)
		(duplicate_pad_numbers_are_jumpers no)
		(fp_line
			(start -0.7874 0.4064)
			(end -0.7874 -0.4064)
			(stroke
				(width 0.1524)
				(type default)
			)
			(layer "F.SilkS")
		)
		(fp_line
			(start 0.7874 0.4064)
			(end -0.7874 0.4064)
			(stroke
				(width 0.1524)
				(type default)
			)
			(layer "F.SilkS")
		)
		(fp_line
			(start -0.7874 -0.4064)
			(end 0.7874 -0.4064)
			(stroke
				(width 0.1524)
				(type default)
			)
			(layer "F.SilkS")
		)
		(fp_line
			(start 0.7874 -0.4064)
			(end 0.7874 0.4064)
			(stroke
				(width 0.1524)
				(type default)
			)
			(layer "F.SilkS")
		)
		(fp_poly
			(pts
				(xy -0.508 0.2794) (xy -0.508 0.2286) (xy -0.635 0.2286) (xy -0.635 -0.254) (xy -0.5334 -0.254)
				(xy -0.5334 -0.2794) (xy 0.5334 -0.2794) (xy 0.5334 -0.254) (xy 0.635 -0.254) (xy 0.635 0.254) (xy 0.5334 0.254)
				(xy 0.5334 0.2794)
			)
			(stroke
				(width 0)
				(type default)
			)
			(fill no)
			(layer "F.CrtYd")
		)
		(pad "1" smd rect
			(at 0.40005 0 270)
			(size 0.4572 0.508)
			(layers "F.Cu" "F.Mask" "F.Paste")
			(net "PSU5_REMOTE_N")
		)
		(pad "2" smd rect
			(at -0.40005 0 270)
			(size 0.4572 0.508)
			(layers "F.Cu" "F.Mask" "F.Paste")
			(net "PSU5_REMOTE_R_N")
		)
	)
)
